%FSTAX23Y23*%
%MOIN*%
%SFA1B1*%

%IPPOS*%
%ADD17C,0.006000*%
%ADD19C,0.005000*%
%ADD22C,0.008000*%
%ADD162C,0.020000*%
%ADD170C,0.061020*%
%ADD172C,0.075000*%
%ADD178R,0.055000X0.055000*%
%ADD181C,0.016000*%
%LNtimingcard_pcb-1*%
%LPD*%
G54D17*
X02083Y01411D02*
X02084Y01412D01*
Y03895*
X02084Y03896*
G54D19*
X02496Y0039D02*
D01*
X02497Y0039*
X02498Y0039*
X02499Y0039*
X025Y0039*
X02501Y00391*
X02502Y00391*
X02503Y00392*
X02504Y00392*
X02505Y00393*
X02506Y00393*
X02507Y00394*
X02507Y00395*
X02508Y00396*
X02509Y00396*
X02509Y00397*
X0251Y00398*
X0251Y00399*
X02511Y004*
X02511Y00401*
X02511Y00402*
X02511Y00403*
X02511Y00404*
X02511Y00405*
X02466Y0073D02*
D01*
X02459Y00722*
X02453Y00715*
X02447Y00707*
X02442Y00698*
X02438Y0069*
X02434Y00681*
X02431Y00671*
X02428Y00662*
X02426Y00652*
X02425Y00643*
X02425Y00633*
X02425Y0063*
Y00436D02*
D01*
X02425Y00433*
X02425Y0043*
X02426Y00427*
X02427Y00423*
X02428Y0042*
X02429Y00417*
X0243Y00414*
X02432Y00412*
X02434Y00409*
X02436Y00406*
X02438Y00404*
X0244Y00402*
X02443Y004*
X02445Y00398*
X02448Y00396*
X02451Y00394*
X02454Y00393*
X02457Y00392*
X0246Y00391*
X02463Y0039*
X02466Y0039*
X0247Y0039*
X02471Y0039*
X02953Y00399D02*
D01*
X02953Y00399*
X02953Y00399*
X02953Y00399*
X02953Y00399*
X02953Y00399*
X02974Y00391D02*
D01*
X02976Y00391*
X02977Y0039*
X02978Y0039*
X02979Y0039*
X02981Y0039*
X02982Y0039*
X02983Y0039*
X02954Y00399D02*
D01*
X02957Y00397*
X02961Y00395*
X02964Y00394*
X02968Y00393*
X02971Y00392*
X02974Y00391*
X02925Y0047D02*
D01*
X02925Y00462*
X02926Y00455*
X02927Y00449*
X02929Y00442*
X02931Y00435*
X02933Y00429*
X02936Y00422*
X0294Y00416*
X02944Y0041*
X02948Y00405*
X02953Y00399*
X02953Y00399*
X02984Y00391D02*
D01*
X02984Y0039*
X02983Y0039*
X02983Y0039*
X02984Y00391D02*
D01*
X02988Y00391*
X02991Y00391*
X02995Y00392*
X02999Y00393*
X03002Y00394*
X03006Y00396*
X03009Y00398*
X03012Y004*
X03015Y00402*
X03018Y00404*
X03019Y00405*
X02953Y00399D02*
D01*
X02954Y00399*
X02954Y00399*
X02954Y00399*
X02954Y00399*
X02954Y00399*
X02974Y00391D02*
D01*
X02974Y00391*
X02974Y00391*
X02974Y00391*
X02979Y00409D02*
D01*
X02979Y00409*
X02979Y00409*
X02979Y00409*
X0298Y00409*
X0298Y00409*
X0298Y00409*
X02966Y00443D02*
D01*
X02966Y00443*
X02965Y00443*
X02965Y00443*
X02964Y00443*
X02964Y00442*
X02963Y00442*
X02963Y00442*
X02962Y00442*
X02962Y00441*
X02961Y00441*
X02961Y00441*
X02961Y0044*
X0296Y0044*
X0296Y0044*
X0296Y00439*
X02959Y00439*
X02959Y00438*
X02959Y00438*
X02959Y00437*
X02959Y00437*
X02959Y00436*
X02959Y00436*
Y00435*
X02959Y00435*
X02959Y00434*
X02959Y00434*
X02959Y00433*
X02959Y00433*
X02975Y00412D02*
D01*
X02976Y00411*
X02977Y00411*
X02977Y0041*
X02978Y0041*
X02979Y00409*
X02966Y00443D02*
D01*
X02967Y00443*
X02967Y00443*
X02968Y00443*
X02968Y00443*
X02969Y00443*
X02969Y00444*
X0297Y00444*
X0297Y00444*
X02971Y00444*
X02971Y00445*
X02971Y00445*
X02972Y00445*
X02972Y00446*
X02972Y00446*
X02973Y00447*
X02973Y00447*
X02973Y00448*
X02973Y00448*
X02974Y00449*
X02974Y00449*
X02974Y0045*
X02974Y0045*
Y00451*
X02974Y00451*
X02974Y00452*
X02974Y00452*
X02973Y00453*
X02973Y00453*
X02973Y00454*
X02973Y00454*
X02972Y00455*
X02972Y00455*
X02972Y00455*
X02971Y00456*
X02971Y00456*
X02971Y00456*
X0297Y00457*
X0297Y00457*
X02969Y00457*
X02969Y00457*
X02968Y00458*
X02968Y00458*
X02967Y00458*
X02967Y00458*
X02966Y00458*
X02945Y00473D02*
D01*
X02944Y00473*
X02944Y00473*
X02943Y00473*
X02943Y00473*
X02942Y00472*
X02942Y00472*
X02941Y00472*
X02941Y00472*
X0294Y00471*
X0294Y00471*
X0294Y00471*
X02939Y0047*
X02939Y0047*
X02939Y0047*
X02938Y00469*
X02938Y00469*
X02938Y00468*
X02938Y00468*
X02937Y00467*
X02937Y00467*
X02937Y00466*
X02937Y00466*
Y00465*
X02937Y00465*
X02937Y00464*
X02937Y00464*
X02938Y00463*
X02938Y00463*
X02938Y00462*
X02938Y00462*
X02939Y00461*
X02939Y00461*
X02939Y0046*
X0294Y0046*
X0294Y0046*
X0294Y00459*
X02941Y00459*
X02941Y00459*
X02942Y00459*
X02942Y00458*
X02943Y00458*
X02943Y00458*
X02944Y00458*
X02944Y00458*
X02945Y00458*
X02955Y00473D02*
D01*
X02955Y00473*
X02956Y00473*
X02956Y00473*
X02957Y00473*
X02957Y00473*
X02958Y00474*
X02958Y00474*
X02959Y00474*
X02959Y00474*
X02959Y00475*
X0296Y00475*
X0296Y00475*
X02961Y00476*
X02961Y00476*
X02961Y00477*
X02961Y00477*
X02962Y00478*
X02962Y00478*
X02962Y00479*
X02962Y00479*
X02962Y0048*
X02962Y0048*
Y00481*
X02962Y00481*
X02962Y00482*
X02962Y00482*
X02962Y00483*
X02962Y00483*
X02961Y00484*
X02961Y00484*
X02961Y00485*
X02961Y00485*
X0296Y00485*
X0296Y00486*
X02959Y00486*
X02959Y00486*
X02959Y00487*
X02958Y00487*
X02958Y00487*
X02957Y00487*
X02957Y00488*
X02956Y00488*
X02956Y00488*
X02955Y00488*
X02955Y00488*
X02938Y00493D02*
D01*
X02938Y00492*
X02938Y00492*
X02938Y00491*
X02938Y00491*
X02939Y00491*
X02939Y0049*
X0294Y0049*
X0294Y00489*
X0294Y00489*
X02941Y00489*
X02941Y00489*
X02942Y00488*
X02942Y00488*
X02943Y00488*
X02943Y00488*
X02944Y00488*
X02944Y00488*
X02945Y00488*
X02847Y00436D02*
D01*
X02847Y00437*
X02846Y00437*
X02846Y00437*
X02845Y00438*
X02845Y00438*
X02844Y00438*
X02844Y00438*
X02843Y00438*
X02843Y00439*
X02842Y00439*
X02842Y00439*
X02841Y00439*
X02841Y00439*
X0284Y00438*
X0284Y00438*
X02839Y00438*
X02839Y00438*
X02838Y00438*
X02838Y00438*
X02837Y00437*
X02837Y00437*
X02837Y00437*
X02836Y00436*
X02851Y00432D02*
D01*
X02851Y00432*
X02852Y00432*
X02852Y00431*
X02853Y00431*
X02853Y00431*
X02854Y00431*
X02854Y00431*
X02855Y0043*
X02855Y0043*
X02856Y0043*
X02856Y0043*
X02857Y0043*
X02857Y0043*
X02858Y0043*
X02858Y0043*
X02859Y00431*
X02859Y00431*
X0286Y00431*
X0286Y00431*
X02861Y00432*
X02861Y00432*
X02861Y00432*
X02862Y00432*
D01*
X02862Y00433*
X02862Y00433*
X02863Y00434*
X02863Y00434*
X02863Y00435*
X02863Y00435*
X02863Y00436*
X02864Y00436*
X02864Y00437*
X02864Y00437*
X02864Y00438*
X02864Y00438*
X02864Y00439*
X02864Y00439*
X02864Y0044*
X02863Y0044*
X02863Y00441*
X02863Y00441*
X02863Y00442*
X02862Y00442*
X02862Y00442*
X02862Y00443*
X02862Y00443*
X02856Y0046D02*
D01*
X02855Y00459*
X02855Y00459*
X02855Y00458*
X02854Y00458*
X02854Y00457*
X02854Y00457*
X02854Y00457*
X02854Y00456*
X02854Y00455*
X02853Y00455*
X02853Y00454*
X02853Y00454*
X02854Y00453*
X02854Y00453*
X02854Y00452*
X02854Y00452*
X02854Y00451*
X02854Y00451*
X02855Y0045*
X02855Y0045*
X02855Y0045*
X02855Y00449*
X02856Y00449*
X02866Y0046D02*
D01*
X02866Y0046*
X02865Y0046*
X02865Y00461*
X02865Y00461*
X02864Y00461*
X02864Y00461*
X02863Y00461*
X02863Y00462*
X02862Y00462*
X02862Y00462*
X02861Y00462*
X02861Y00462*
X0286Y00462*
X0286Y00462*
X02859Y00462*
X02858Y00461*
X02858Y00461*
X02858Y00461*
X02857Y00461*
X02857Y0046*
X02856Y0046*
X02856Y0046*
X02856Y0046*
X02872Y00454D02*
D01*
X02873Y00453*
X02873Y00453*
X02873Y00453*
X02874Y00452*
X02874Y00452*
X02875Y00452*
X02875Y00452*
X02876Y00452*
X02876Y00452*
X02877Y00451*
X02877Y00451*
X02878Y00451*
X02878Y00451*
X02879Y00452*
X02879Y00452*
X0288Y00452*
X0288Y00452*
X02881Y00452*
X02881Y00452*
X02882Y00453*
X02882Y00453*
X02883Y00453*
X02883Y00454*
D01*
X02883Y00454*
X02884Y00454*
X02884Y00455*
X02884Y00455*
X02884Y00456*
X02885Y00456*
X02885Y00457*
X02885Y00457*
X02885Y00458*
X02885Y00458*
X02885Y00459*
X02885Y00459*
X02885Y0046*
X02885Y0046*
X02885Y00461*
X02885Y00461*
X02884Y00462*
X02884Y00462*
X02884Y00463*
X02884Y00463*
X02883Y00464*
X02883Y00464*
X02883Y00464*
X02879Y00479D02*
D01*
X02878Y00478*
X02878Y00478*
X02878Y00478*
X02878Y00477*
X02877Y00477*
X02877Y00476*
X02877Y00476*
X02877Y00475*
X02877Y00475*
X02877Y00474*
X02877Y00474*
X02877Y00473*
X02877Y00473*
X02877Y00472*
X02877Y00472*
X02877Y00471*
X02877Y00471*
X02877Y0047*
X02878Y0047*
X02878Y00469*
X02878Y00469*
X02879Y00468*
X02879Y00468*
X02803Y00407D02*
D01*
X02803Y00406*
X02803Y00404*
X02804Y00403*
X02804Y00401*
X02805Y004*
X02805Y00398*
X02806Y00397*
X02807Y00396*
X02808Y00394*
X02809Y00393*
X02809Y00393*
X02811Y0043D02*
D01*
X0281Y00428*
X02809Y00426*
X02808Y00425*
X02806Y00423*
X02806Y00421*
X02805Y00419*
X02804Y00417*
X02804Y00415*
X02803Y00413*
X02803Y00411*
X02803Y00409*
X02803Y00407*
X0287Y00489D02*
D01*
X02871Y00489*
X02871Y00489*
X02871Y00489*
X02871Y0049*
X02871Y0049*
X02872Y0049*
X02872Y00491*
X02872Y00491*
X02872Y00491*
X02872Y00492*
X02872Y00492*
X02872Y00492*
X02809Y00393D02*
D01*
X0281Y00392*
X02812Y00391*
X02813Y0039*
X02814Y00389*
X02816Y00389*
X02817Y00388*
X02818Y00387*
X0282Y00387*
X02822Y00387*
X02823Y00387*
X02825Y00387*
X02826Y00387*
X02828Y00387*
X02829Y00387*
X02831Y00387*
X02832Y00388*
X02834Y00388*
X02835Y00389*
X02836Y0039*
X02838Y00391*
X02839Y00392*
X0284Y00393*
X02881Y00482D02*
D01*
X02881Y00482*
X02881Y00482*
X02881Y00482*
X02881Y00482*
X02881Y00482*
X02734Y00406D02*
D01*
X02734Y00407*
X02735Y00407*
X02735Y00407D02*
D01*
X02735Y00407*
X02735Y00408*
X02735Y00408*
X02735Y00408*
X02736Y00408*
X02736Y00408*
X0274Y00435D02*
D01*
X0274Y00436*
X0274Y00436*
X0274Y00437*
X0274Y00438*
X0274Y00438*
X02739Y00439*
X02739Y00439*
X02739Y00439*
X02739Y0044*
X02738Y0044*
X02738Y00441*
X02738Y00441*
X02737Y00441*
X02737Y00442*
X02736Y00442*
X02736Y00442*
X02735Y00442*
X02735Y00443*
X02734Y00443*
X02734Y00443*
X02733Y00443*
X02733Y00443*
X02733Y00443*
Y00458D02*
D01*
X02732Y00458*
X02732Y00458*
X02731Y00458*
X0273Y00458*
X0273Y00457*
X0273Y00457*
X02729Y00457*
X02729Y00457*
X02728Y00457*
X02728Y00456*
X02727Y00456*
X02727Y00455*
X02727Y00455*
X02726Y00455*
X02726Y00454*
X02726Y00454*
X02726Y00453*
X02725Y00453*
X02725Y00452*
X02725Y00452*
X02725Y00451*
X02725Y00451*
Y0045*
X02725Y0045*
X02725Y00449*
X02725Y00449*
X02725Y00448*
X02726Y00448*
X02726Y00447*
X02726Y00447*
X02726Y00446*
X02727Y00446*
X02727Y00445*
X02727Y00445*
X02728Y00445*
X02728Y00444*
X02729Y00444*
X02729Y00444*
X0273Y00444*
X0273Y00443*
X0273Y00443*
X02731Y00443*
X02732Y00443*
X02732Y00443*
X02733Y00443*
X02734Y00458D02*
D01*
X02734Y00458*
X02735Y00458*
X02735Y00458*
X02736Y00458*
X02736Y00458*
X02737Y00459*
X02737Y00459*
X02738Y00459*
X02738Y00459*
X02738Y0046*
X02739Y0046*
X02739Y0046*
X02739Y00461*
X0274Y00461*
X0274Y00462*
X0274Y00462*
X02741Y00463*
X02741Y00463*
X02741Y00464*
X02741Y00464*
X02741Y00465*
X02741Y00465*
Y00466*
X02741Y00466*
X02741Y00467*
X02741Y00467*
X02741Y00468*
X02741Y00468*
X0274Y00469*
X0274Y00469*
X0274Y0047*
X02739Y0047*
X02739Y0047*
X02739Y00471*
X02738Y00471*
X02738Y00472*
X02738Y00472*
X02737Y00472*
X02737Y00472*
X02736Y00472*
X02736Y00473*
X02735Y00473*
X02735Y00473*
X02734Y00473*
X02734Y00473*
X02732Y00488D02*
D01*
X02731Y00488*
X02731Y00488*
X0273Y00488*
X0273Y00488*
X02729Y00487*
X02729Y00487*
X02728Y00487*
X02728Y00487*
X02727Y00487*
X02727Y00486*
X02727Y00486*
X02726Y00485*
X02726Y00485*
X02725Y00485*
X02725Y00484*
X02725Y00484*
X02725Y00483*
X02725Y00483*
X02724Y00482*
X02724Y00482*
X02724Y00481*
X02724Y00481*
Y0048*
X02724Y0048*
X02724Y00479*
X02724Y00479*
X02725Y00478*
X02725Y00478*
X02725Y00477*
X02725Y00477*
X02725Y00476*
X02726Y00476*
X02726Y00475*
X02727Y00475*
X02727Y00475*
X02727Y00474*
X02728Y00474*
X02728Y00474*
X02729Y00474*
X02729Y00473*
X0273Y00473*
X0273Y00473*
X02731Y00473*
X02731Y00473*
X02732Y00473*
X02734Y00488D02*
D01*
X02734Y00488*
X02735Y00488*
X02735Y00488*
X02736Y00488*
X02736Y00488*
X02737Y00489*
X02737Y00489*
X02738Y00489*
X02738Y00489*
X02738Y0049*
X02739Y0049*
X02739Y0049*
X02739Y00491*
X0274Y00491*
X0274Y00492*
X0274Y00492*
X02741Y00493*
X02741Y00493*
X02741Y00494*
X02741Y00494*
X02741Y00495*
X02741Y00495*
Y00496*
X02741Y00496*
X02741Y00497*
X02741Y00497*
X02741Y00498*
X02741Y00498*
X0274Y00499*
X0274Y00499*
X0274Y005*
X02739Y005*
X02739Y005*
X02739Y00501*
X02738Y00501*
X02738Y00502*
X02738Y00502*
X02737Y00502*
X02737Y00502*
X02736Y00502*
X02736Y00503*
X02735Y00503*
X02735Y00503*
X02734Y00503*
X02734Y00503*
X02731Y00518D02*
D01*
X0273Y00518*
X0273Y00518*
X02729Y00518*
X02728Y00518*
X02728Y00517*
X02727Y00517*
X02727Y00517*
X02727Y00517*
X02726Y00517*
X02726Y00516*
X02725Y00516*
X02725Y00515*
X02725Y00515*
X02724Y00515*
X02724Y00514*
X02724Y00514*
X02724Y00513*
X02723Y00513*
X02723Y00512*
X02723Y00512*
X02723Y00511*
X02723Y00511*
Y0051*
X02723Y0051*
X02723Y00509*
X02723Y00509*
X02723Y00508*
X02724Y00508*
X02724Y00507*
X02724Y00507*
X02724Y00506*
X02725Y00506*
X02725Y00505*
X02725Y00505*
X02726Y00505*
X02726Y00504*
X02727Y00504*
X02727Y00504*
X02727Y00504*
X02728Y00503*
X02728Y00503*
X02729Y00503*
X0273Y00503*
X0273Y00503*
X02731Y00503*
X02733Y00518D02*
D01*
X02733Y00518*
X02734Y00518*
X02734Y00518*
X02735Y00518*
X02735Y00518*
X02736Y00519*
X02736Y00519*
X02737Y00519*
X02737Y00519*
X02737Y0052*
X02738Y0052*
X02738Y0052*
X02738Y00521*
X02739Y00521*
X02739Y00522*
X02739Y00522*
X0274Y00523*
X0274Y00523*
X0274Y00524*
X0274Y00524*
X0274Y00525*
X0274Y00525*
X0274Y00525*
X02704Y00405D02*
D01*
X02705Y00404*
X02706Y00403*
X02708Y00402*
X02709Y00402*
X0271Y00401*
X02711Y004*
X02713Y004*
X02714Y004*
X02716Y00399*
X02717Y00399*
X02718Y00399*
X0272Y00399*
X02721Y00399*
X02723Y004*
X02724Y004*
X02725Y004*
X02727Y00401*
X02728Y00401*
X02729Y00402*
X0273Y00403*
X02732Y00404*
X02733Y00405*
X02734Y00406*
X02409Y00366D02*
D01*
X02409Y00365*
X0241Y00365*
X0241Y00365*
X02411Y00364*
X02411Y00364*
X02419Y00362D02*
D01*
X02419Y00362*
X0242Y00362*
X0242Y00362*
X02421Y00362*
X02421Y00362*
X02422Y00362*
X02422Y00362*
X02423Y00362*
X02423Y00362*
X02424Y00363*
X02424Y00363*
X02425Y00363*
X02425Y00363*
X02425Y00364*
X02426Y00364*
X02426Y00365*
X02427Y00365*
X02427Y00365*
X02427Y00366*
X02427Y00366*
X02428Y00367*
X02428Y00367*
X02428Y00368*
X02428Y00368*
X02428Y00369*
X02428Y00369*
X02428Y00369*
X02443Y00372D02*
D01*
X02443Y00372*
X02443Y00373*
X02443Y00373*
X02443Y00374*
X02443Y00374*
X02442Y00375*
X02442Y00375*
X02442Y00376*
X02442Y00376*
X02441Y00377*
X02441Y00377*
X02441Y00377*
X0244Y00378*
X0244Y00378*
X02439Y00378*
X02439Y00378*
X02438Y00379*
X02438Y00379*
X02437Y00379*
X02437Y00379*
X02436Y00379*
X02436Y00379*
X02435*
X02435Y00379*
X02434Y00379*
X02434Y00379*
X02433Y00379*
X02433Y00379*
X02432Y00378*
X02432Y00378*
X02431Y00378*
X02431Y00378*
X02431Y00377*
X0243Y00377*
X0243Y00377*
X02429Y00376*
X02429Y00376*
X02429Y00375*
X02429Y00375*
X02429Y00374*
X02428Y00374*
X02428Y00373*
X02428Y00373*
X02428Y00372*
X02428Y00372*
X02443Y00361D02*
D01*
X02443Y00361*
X02443Y0036*
X02443Y0036*
X02443Y00359*
X02444Y00359*
X02444Y00358*
X02444Y00358*
X02444Y00357*
X02444Y00357*
X02445Y00356*
X02445Y00356*
X02446Y00356*
X02446Y00355*
X02446Y00355*
X02447Y00355*
X02447Y00355*
X02448Y00354*
X02448Y00354*
X02449Y00354*
X02397Y00376D02*
D01*
X02401Y00372*
X02405Y00369*
X02409Y00366*
X02409Y00366*
X02444Y00505D02*
D01*
X02444Y00505*
X02444Y00504*
X02445Y00504*
X02445Y00503*
X02445Y00503*
X02445Y00502*
X02445Y00502*
X02446Y00501*
X02446Y00501*
X02446Y005*
X02446Y005*
X02447Y005*
X02447Y00499*
X02448Y00499*
X02448Y00499*
X02449Y00498*
X02449Y00498*
X0245Y00498*
X0245Y00498*
X02451Y00498*
X02451Y00498*
X02452Y00498*
X02452Y00498*
X02456Y00483D02*
D01*
X02457Y00483*
X02457Y00483*
X02458Y00483*
X02458Y00483*
X02459Y00483*
X02459Y00483*
X0246Y00484*
X0246Y00484*
X02461Y00484*
X02461Y00484*
X02461Y00485*
X02462Y00485*
X02462Y00486*
X02462Y00486*
X02463Y00486*
X02463Y00487*
X02463Y00487*
X02463Y00488*
X02463Y00488*
X02464Y00489*
X02464Y00489*
X02464Y0049*
Y0049*
X02464Y00491*
X02464Y00491*
X02463Y00492*
X02463Y00492*
X02463Y00493*
X02463Y00493*
X02463Y00494*
X02462Y00494*
X02462Y00495*
X02462Y00495*
X02461Y00496*
X02461Y00496*
X02461Y00496*
X0246Y00497*
X0246Y00497*
X02459Y00497*
X02459Y00497*
X02458Y00497*
X02458Y00497*
X02457Y00498*
X02457Y00498*
X02456Y00498*
X02442Y00483D02*
D01*
X02442Y00483*
X02441Y00483*
X02441Y00482*
X0244Y00482*
X0244Y00482*
X02439Y00482*
X02439Y00482*
X02438Y00482*
X02438Y00481*
X02437Y00481*
X02437Y00481*
X02437Y0048*
X02436Y0048*
X02436Y00479*
X02436Y00479*
X02435Y00478*
X02435Y00478*
X02435Y00477*
X02435Y00477*
X02435Y00476*
X02435Y00476*
X02435Y00475*
Y00475*
X02435Y00474*
X02435Y00474*
X02435Y00473*
X02435Y00473*
X02435Y00472*
X02435Y00472*
X02436Y00471*
X02436Y00471*
X02436Y00471*
X02437Y0047*
X02437Y0047*
X02437Y00469*
X02438Y00469*
X02438Y00469*
X02439Y00469*
X02439Y00468*
X0244Y00468*
X0244Y00468*
X02441Y00468*
X02441Y00468*
X02442Y00468*
X02442Y00468*
X02458Y00453D02*
D01*
X02459Y00453*
X02459Y00453*
X0246Y00453*
X0246Y00453*
X02461Y00453*
X02461Y00453*
X02462Y00454*
X02462Y00454*
X02463Y00454*
X02463Y00454*
X02464Y00455*
X02464Y00455*
X02464Y00456*
X02465Y00456*
X02465Y00456*
X02465Y00457*
X02465Y00457*
X02465Y00458*
X02466Y00458*
X02466Y00459*
X02466Y00459*
X02466Y0046*
Y0046*
X02466Y00461*
X02466Y00461*
X02466Y00462*
X02465Y00462*
X02465Y00463*
X02465Y00463*
X02465Y00464*
X02465Y00464*
X02464Y00465*
X02464Y00465*
X02464Y00466*
X02463Y00466*
X02463Y00466*
X02462Y00467*
X02462Y00467*
X02461Y00467*
X02461Y00467*
X0246Y00467*
X0246Y00467*
X02459Y00468*
X02459Y00468*
X02458Y00468*
X02452Y00453D02*
D01*
X02451Y00453*
X02451Y00453*
X0245Y00452*
X0245Y00452*
X02449Y00452*
X02449Y00452*
X02448Y00452*
X02448Y00452*
X02447Y00451*
X02447Y00451*
X02447Y00451*
X02446Y0045*
X02446Y0045*
X02446Y00449*
X02445Y00449*
X02445Y00448*
X02445Y00448*
X02445Y00447*
X02445Y00447*
X02444Y00446*
X02444Y00446*
X02444Y00445*
X02444Y00445*
Y00423D02*
D01*
X02444Y00423*
X02444Y00423*
X02444Y00422*
X02445Y00422*
X02445Y00421*
X02445Y00421*
X02445Y00421*
X02445Y0042*
X02445Y0042*
X02446Y0042*
X02446Y0042*
X02446Y00419*
X02446Y00419*
X02474Y00722D02*
D01*
X02469Y00717*
X02465Y00711*
X02461Y00706*
X02457Y007*
X02454Y00693*
X02451Y00687*
X02449Y0068*
X02447Y00674*
X02446Y00667*
X02445Y0066*
X02444Y00653*
X02444Y00651*
X02453Y00414D02*
D01*
X02453Y00414*
X02453Y00414*
X02453Y00414*
X02453Y00414*
X02453Y00414*
X02453Y00414D02*
D01*
X02454Y00413*
X02455Y00412*
X02456Y00412*
X02457Y00411*
X02458Y00411*
X02459Y0041*
X0246Y0041*
X02461Y0041*
X02463Y0041*
X02464Y0041*
X02465Y0041*
X02466Y0041*
X02467Y0041*
X02468Y0041*
X02469Y0041*
X02881Y00482D02*
D01*
X02882Y00482*
X02882Y00482*
X02882Y00482*
X02882Y00483*
X02882Y00483*
X02883Y00483*
X02883Y00484*
X02883Y00484*
X02883Y00484*
X02883Y00485*
X02883Y00485*
X02883Y00485*
X02872Y0077D02*
D01*
X02872Y00772*
X02872Y00775*
X02871Y00777*
X02871Y0078*
X0287Y00782*
X02869Y00784*
X02868Y00786*
X02867Y00789*
X02865Y00791*
X02864Y00793*
X02862Y00794*
X02862Y00795*
X02849Y00403D02*
D01*
X02849Y00403*
X0285Y00403*
X0285Y00403*
X02851Y00403*
X02851Y00403*
X02852Y00404*
X02852Y00404*
X02853Y00404*
X02853Y00404*
X02853Y00405*
X02854Y00405*
X02854Y00405*
X02848Y00403D02*
D01*
X02847Y00403*
X02847Y00403*
X02846Y00403*
X02846Y00403*
X02846Y00403*
X02845Y00402*
X02845Y00402*
X02844Y00402*
X02844Y00402*
X02844Y00402*
X02843Y00401*
X02843Y00401*
D01*
X02843Y00401*
X02843Y00401*
X02843Y004*
X02842Y004*
X02842Y004*
X02842Y00399*
X02842Y00399*
X02842Y00398*
X02842Y00398*
X02842Y00398*
X02842Y00397*
X02842Y00397*
X0284Y00393D02*
D01*
X0284Y00393*
X0284Y00393*
X02841Y00393*
X02841Y00394*
X02841Y00394*
X02841Y00394*
X02841Y00395*
X02841Y00395*
X02842Y00395*
X02842Y00396*
X02842Y00396*
X02842Y00396*
X02735Y00392D02*
D01*
X02737Y00393*
X02739Y00395*
X0274Y00396*
X02742Y00398*
X02744Y004*
X02745Y00402*
X02746Y00404*
X02748Y00407*
X02749Y00409*
X02749Y00411*
X0275Y00414*
X02751Y00416*
X02751Y00418*
X02751Y00421*
X02751Y00422*
X02671Y00399D02*
D01*
X02674Y00396*
X02676Y00394*
X02679Y00392*
X02682Y0039*
X02686Y00389*
X02689Y00387*
X02692Y00386*
X02696Y00385*
X02699Y00384*
X02703Y00384*
X02706Y00384*
X0271Y00384*
X02713Y00384*
X02717Y00385*
X0272Y00386*
X02724Y00387*
X02727Y00388*
X0273Y00389*
X02733Y00391*
X02735Y00392*
X02759Y00795D02*
D01*
X02758Y00793*
X02757Y00792*
X02756Y0079*
X02755Y00788*
X02754Y00787*
X02753Y00785*
X02752Y00783*
X02752Y00781*
X02751Y00779*
X02751Y00777*
X02751Y00775*
X02751Y00775*
X02823Y00973D02*
D01*
X02822Y00972*
X02822Y00971*
X02821Y0097*
X0282Y00969*
X0282Y00968*
X02819Y00966*
X02819Y00965*
X02818Y00964*
X02818Y00963*
X02818Y00962*
X02818Y0096*
X02818Y0096*
X02893Y00795D02*
D01*
X02892Y00793*
X0289Y00791*
X02889Y00789*
X02887Y00787*
X02886Y00785*
X02885Y00783*
X02884Y0078*
X02884Y00778*
X02883Y00776*
X02883Y00773*
X02883Y00771*
X02883Y0077*
X0274Y00775D02*
D01*
X0274Y00777*
X0274Y00779*
X02739Y00781*
X02739Y00782*
X02738Y00784*
X02738Y00786*
X02737Y00788*
X02736Y0079*
X02735Y00791*
X02733Y00793*
X02732Y00794*
X02732Y00795*
X0235Y00405D02*
D01*
X0235Y00405*
X0235Y00405*
X0235Y00405*
X0235Y00405*
X02351Y00405*
X02351Y00404*
X02351Y00404*
X02351Y00404*
X02351Y00404*
X02351Y00404*
X02351Y00404*
X02352Y00404*
X02363Y00403D02*
D01*
X02362Y00403*
X02362Y00403*
X02362Y00404*
X02361Y00404*
X02361Y00404*
X02361Y00404*
X02361Y00404*
X0236Y00404*
X0236Y00404*
X0236Y00404*
X02359Y00404*
X02359Y00404*
X02364Y00399D02*
D01*
X02364Y004*
X02364Y004*
X02364Y004*
X02364Y00401*
X02364Y00401*
X02364Y00401*
X02363Y00402*
X02363Y00402*
X02363Y00402*
X02363Y00403*
X02363Y00403*
X02363Y00403*
X02364Y00397D02*
D01*
X02364Y00396*
X02364Y00396*
X02364Y00395*
X02364Y00394*
X02365Y00393*
X02365Y00393*
X02365Y00392*
X02366Y00392*
X02366Y00391*
X02367Y0039*
X02367Y0039*
X02367Y0039*
X02389Y00368D02*
D01*
X02393Y00364*
X02398Y0036*
X02403Y00357*
X02408Y00353*
X02413Y00351*
X02419Y00348*
X02424Y00347*
X0243Y00345*
X02436Y00344*
X02442Y00343*
X02448Y00343*
X02449Y00343*
X02535D02*
D01*
X02536Y00343*
X02536Y00343*
X02537Y00343*
X02538Y00343*
X02539Y00343*
X02539Y00344*
X0254Y00344*
X02541Y00344*
X02541Y00345*
X02542Y00345*
X02543Y00346*
X02543Y00346*
X02585Y00388D02*
D01*
X0259Y00394*
X02595Y004*
X02599Y00406*
X02603Y00413*
X02607Y0042*
X0261Y00427*
X02612Y00434*
X02614Y00442*
X02616Y00449*
X02617Y00457*
X02617Y00465*
X02617Y00466*
X02625Y00795D02*
D01*
X02624Y00793*
X02623Y00792*
X02622Y0079*
X02621Y00788*
X0262Y00787*
X02619Y00785*
X02618Y00783*
X02618Y00781*
X02618Y00779*
X02617Y00777*
X02617Y00775*
X02617Y00775*
X02388Y00404D02*
D01*
X02388Y00404*
X02388Y00404*
X02388Y00404*
X02388Y00404*
X02388Y00404*
X02389Y00405*
X02389Y00405*
X02389Y00405*
X02389Y00405*
X02389Y00405*
X02389Y00405*
X02389Y00405*
X0238Y00404D02*
D01*
X0238Y00404*
X02379Y00404*
X02379Y00404*
X02379Y00404*
X02378Y00404*
X02378Y00404*
X02378Y00404*
X02377Y00404*
X02377Y00403*
X02377Y00403*
X02377Y00403*
X02377Y00403*
D01*
X02376Y00403*
X02376Y00402*
X02376Y00402*
X02376Y00402*
X02376Y00401*
X02375Y00401*
X02375Y00401*
X02375Y004*
X02375Y004*
X02375Y004*
X02375Y00399*
X02375Y00399*
D01*
X02375Y00399*
X02375Y00399*
X02375Y00398*
X02375Y00398*
X02375Y00398*
X02376Y00397*
X02376Y00397*
X02376Y00397*
X02376Y00396*
X02376Y00396*
X02376Y00396*
X02377Y00396*
X02577D02*
D01*
X02582Y00401*
X02586Y00406*
X0259Y00412*
X02594Y00418*
X02597Y00424*
X026Y00431*
X02602Y00437*
X02604Y00444*
X02605Y00451*
X02606Y00458*
X02606Y00465*
X02606Y00467*
Y00775D02*
D01*
X02606Y00777*
X02606Y00779*
X02606Y00781*
X02605Y00782*
X02604Y00784*
X02604Y00786*
X02603Y00788*
X02602Y0079*
X02601Y00791*
X026Y00793*
X02598Y00794*
X02598Y00795*
X02818Y0096D02*
D01*
X02818Y00959*
X02818Y00958*
X02818Y00956*
X02819Y00955*
X02819Y00954*
X0282Y00953*
X0282Y00952*
X02821Y00951*
X02821Y0095*
X02822Y00949*
X02823Y00948*
X02823Y00947*
X02925Y00789D02*
D01*
X02924Y00796*
X02924Y00803*
X02923Y0081*
X02921Y00817*
X02919Y00823*
X02916Y0083*
X02913Y00836*
X0291Y00842*
X02906Y00848*
X02901Y00853*
X02897Y00858*
X02895Y0086*
X02807Y00958D02*
D01*
X02807Y00956*
X02807Y00955*
X02808Y00953*
X02808Y00951*
X02808Y0095*
X02809Y00948*
X0281Y00947*
X02811Y00945*
X02811Y00944*
X02812Y00943*
X02814Y00942*
X02814Y00941*
X02807Y00958D02*
D01*
X02807Y00959*
X02807Y00961*
X02806Y00963*
X02806Y00964*
X02806Y00966*
X02805Y00967*
X02804Y00969*
X02803Y0097*
X02803Y00972*
X02802Y00973*
X028Y00974*
X028Y00974*
X02936Y00808D02*
D01*
X02936Y00813*
X02935Y00817*
X02934Y00822*
X02933Y00826*
X02932Y0083*
X0293Y00834*
X02928Y00839*
X02926Y00842*
X02923Y00846*
X02921Y0085*
X02918Y00853*
X02917Y00854*
X02689Y0096D02*
D01*
X02689Y00961*
X02689Y00963*
X02688Y00964*
X02688Y00965*
X02688Y00966*
X02687Y00967*
X02687Y00968*
X02686Y0097*
X02685Y00971*
X02685Y00972*
X02684Y00972*
X02684Y00973*
Y00947D02*
D01*
X02684Y00948*
X02685Y00949*
X02686Y0095*
X02687Y00951*
X02687Y00953*
X02688Y00954*
X02688Y00955*
X02688Y00956*
X02689Y00957*
X02689Y00958*
X02689Y0096*
X02689Y0096*
X02707Y00974D02*
D01*
X02706Y00973*
X02705Y00972*
X02704Y0097*
X02703Y00969*
X02702Y00968*
X02701Y00966*
X02701Y00965*
X027Y00963*
X027Y00961*
X027Y0096*
X027Y00958*
X027Y00958*
X02693Y00941D02*
D01*
X02694Y00942*
X02695Y00944*
X02696Y00945*
X02697Y00946*
X02698Y00948*
X02698Y00949*
X02699Y00951*
X02699Y00953*
X027Y00954*
X027Y00956*
X027Y00957*
X027Y00958*
X02478Y0039D02*
X02496D01*
X02478D02*
X02478D01*
X02425Y0063D02*
Y00436D01*
X02471Y0039D02*
X02478D01*
X02984Y00391D02*
D01*
X02953Y00399D02*
X02953Y00399D01*
X02983Y0039D02*
D01*
X02925Y0047D02*
Y00789D01*
X02953Y00399D02*
D01*
X02936Y00498D02*
Y00808D01*
X02938Y00493D02*
D01*
X0298Y00409D02*
D01*
X02962Y00424D02*
X02975Y00412D01*
X02959Y00433D02*
X02962Y00424D01*
X02959Y00433D02*
D01*
X02966Y00443D02*
D01*
X02945Y00458D02*
X02966D01*
X02945Y00473D02*
X02955D01*
X02945Y00488D02*
X02955D01*
X02937Y00495D02*
X02938Y00493D01*
X02936Y00498D02*
X02937Y00495D01*
X02818Y00406D02*
X02819Y00407D01*
X02816Y00412D02*
X02816Y00411D01*
X02816Y00412D02*
X02817Y00417D01*
X02836Y00436*
X02847D02*
X02851Y00432D01*
X02856Y00449D02*
X02862Y00443D01*
X02866Y0046D02*
X02872Y00454D01*
X02879Y00468D02*
X02883Y00464D01*
X02879Y00479D02*
D01*
X02881Y00481*
X02821Y00407D02*
X02821D01*
X02821Y00407D02*
X02821Y00407D01*
X02803Y00407D02*
Y00407D01*
X02811Y0043D02*
X0287Y00489D01*
X02811Y0043D02*
X02811Y0043D01*
X02809Y00393D02*
X02809Y00393D01*
X02819Y00407D02*
X02821D01*
X02816Y00411D02*
X02818Y00406D01*
X02872Y00492D02*
Y0077D01*
X02881Y00481D02*
X02881Y00482D01*
X02735Y00407D02*
X02735Y00407D01*
X02736Y00408D02*
X0274Y00423D01*
Y00435*
X02733Y00443D02*
D01*
Y00458D02*
X02734D01*
X02732Y00473D02*
X02734D01*
X02732Y00488D02*
X02734D01*
X02731Y00503D02*
X02734D01*
X02731Y00518D02*
X02733D01*
X0274Y00525D02*
Y00543D01*
Y00775*
X02411Y00364D02*
X02419Y00362D01*
D01*
X02428Y00369D02*
Y00372D01*
X02443Y00361D02*
Y00372D01*
X02449Y00354D02*
D01*
X02449Y00354*
X0246*
X02468*
X02535*
X02444Y00505D02*
Y00562D01*
X02452Y00498D02*
X02456D01*
X02442Y00483D02*
X02456D01*
X02442Y00468D02*
X02458D01*
X02452Y00453D02*
X02458D01*
X02444Y00428D02*
Y00445D01*
Y00562D02*
Y00651D01*
Y00423D02*
Y00428D01*
X02446Y00419D02*
X02453Y00414D01*
X02883Y00509D02*
Y0077D01*
X02751Y00422D02*
Y00775D01*
X02449Y00343D02*
X02535D01*
X02617Y00466D02*
Y00775D01*
X02606Y00467D02*
Y00775D01*
X02476Y0074D02*
X02684Y00947D01*
X02484Y00732D02*
X02693Y00941D01*
X02453Y00414D02*
X02453Y00414D01*
X02466Y0073D02*
X02466Y0073D01*
X02469Y0041D02*
X02469Y0041D01*
X02469Y0041*
X02883Y00485D02*
Y00509D01*
X02893Y00795D02*
Y00795D01*
X02848Y00403D02*
X02849D01*
X02842Y00396D02*
Y00397D01*
X02665Y00405D02*
X02671Y00399D01*
D01*
X02751Y00422D02*
Y00422D01*
X02704Y00405D02*
D01*
X02814Y00941D02*
X02895Y0086D01*
X02466Y0073D02*
X02476Y0074D01*
X02474Y00722D02*
X02484Y00732D01*
X02759Y00795D02*
Y00795D01*
Y00795D02*
D01*
X02732D02*
Y00795D01*
X02352Y00404D02*
X02359D01*
X02364Y00397D02*
Y00399D01*
X02543Y00346D02*
X02585Y00388D01*
X02625Y00795D02*
D01*
Y00795D01*
Y00795D02*
D01*
X0238Y00404D02*
X02388D01*
X02375Y00399D02*
D01*
X02377Y00396D02*
X02397Y00376D01*
X02535Y00354D02*
X02577Y00396D01*
X02598Y00795D02*
Y00795D01*
X02367Y0039D02*
X02389Y00368D01*
X02823Y00973D02*
X02826Y00976D01*
X02799D02*
X028Y00974D01*
X02823Y00947D02*
X02917Y00854D01*
X02826Y00976D02*
Y00976D01*
X02799Y00976D02*
Y00976D01*
X02689Y0096D02*
D01*
X02681Y00976D02*
X02684Y00973D01*
X02707Y00974D02*
X02708Y00976D01*
X02681D02*
Y00976D01*
X02708Y00976D02*
Y00976D01*
G54D22*
X02962Y02292D02*
D01*
X02962Y02293*
X02962Y02293*
X02963Y02294*
X02963Y02294*
X02963Y02294*
X02964Y02295*
X02964Y02296*
X02964Y02296*
X02964Y02297*
X02964Y02297*
X02964Y02298*
X02964Y02298*
X02966Y02447D02*
D01*
X02966Y02446*
X02966Y02446*
X02965Y02445*
X02965Y02445*
X02965Y02444*
X02965Y02444*
X02964Y02443*
X02964Y02443*
X02964Y02442*
X02964Y02442*
X02964Y02441*
X02964Y02441*
X03336Y01952D02*
D01*
X03336Y01952*
X03335Y01951*
X03335Y01951*
X03335Y01951*
X03335Y0195*
X03334Y0195*
X03334Y01949*
X03334Y01948*
X03334Y01948*
X03334Y01947*
X03334Y01947*
X03334Y01946*
X03334Y01946*
X03332Y01829D02*
D01*
X03332Y01829*
X03333Y0183*
X03333Y0183*
X03333Y0183*
X03333Y01831*
X03334Y01831*
X03334Y01832*
X03334Y01833*
X03334Y01833*
X03334Y01834*
X03334Y01834*
X03334Y01834*
Y01941D02*
D01*
X03334Y01941*
X03334Y01941*
X03334Y01941*
X03334Y01942*
X03334Y01942*
X03395Y01951D02*
D01*
X03394Y0195*
X03394Y0195*
X03394Y0195*
X03393Y01949*
X03393Y01949*
X03393Y01948*
X03393Y01948*
X03393Y01947*
X03392Y01946*
X03392Y01946*
X03392Y01945*
X03392Y01945*
X03434Y0199D02*
D01*
X03434Y01991*
X03435Y01991*
X03435Y01992*
X03435Y01992*
X03436Y01993*
X03436Y01993*
X03436Y01994*
X03436Y01994*
X03436Y01995*
X03436Y01995*
X03436Y01996*
X03436Y01996*
X02226Y02444D02*
D01*
X02226Y02445*
X02226Y02445*
X02226Y02446*
X02226Y02446*
X02226Y02447*
X02226Y02447*
X02225Y02448*
X02225Y02448*
X02225Y02449*
X02224Y02449*
X02224Y0245*
X02224Y0245*
X02224Y02417D02*
D01*
X02224Y02417*
X02225Y02418*
X02225Y02418*
X02225Y02419*
X02226Y02419*
X02226Y0242*
X02226Y0242*
X02226Y02421*
X02226Y02421*
X02226Y02422*
X02226Y02422*
X02226Y02423*
X02205Y02472D02*
D01*
X02205Y02471*
X02205Y02471*
X02206Y0247*
X02206Y02469*
X02206Y02469*
X02206Y02468*
X02206Y02468*
X02207Y02467*
X02207Y02467*
X02207Y02466*
X02208Y02466*
X02208Y02466*
X02208Y02401D02*
D01*
X02207Y024*
X02207Y024*
X02207Y02399*
X02206Y02399*
X02206Y02398*
X02206Y02398*
X02206Y02397*
X02206Y02397*
X02205Y02396*
X02205Y02396*
X02205Y02395*
X02205Y02395*
X02528Y02618D02*
D01*
X02527Y02618*
X02527Y02617*
X02527Y02617*
X02526Y02616*
X02526Y02616*
X02526Y02615*
X02526Y02615*
X02526Y02614*
X02525Y02614*
X02525Y02613*
X02525Y02613*
X02525Y02613*
X02664Y02755D02*
D01*
X02665Y02755*
X02665Y02756*
X02666Y02756*
X02666Y02757*
X02666Y02757*
X02666Y02758*
X02666Y02758*
X02667Y02759*
X02667Y02759*
X02667Y0276*
X02667Y02761*
X02667Y02761*
X02552Y02615D02*
D01*
X02551Y02614*
X02551Y02614*
X02551Y02613*
X0255Y02613*
X0255Y02612*
X0255Y02612*
X0255Y02611*
X0255Y02611*
X02549Y0261*
X02549Y0261*
X02549Y02609*
X02549Y02609*
X02684Y02747D02*
D01*
X02685Y02748*
X02685Y02748*
X02685Y02748*
X02686Y02749*
X02686Y02749*
X02686Y0275*
X02686Y0275*
X02686Y02751*
X02686Y02752*
X02686Y02752*
X02687Y02753*
X02687Y02753*
X02294Y03901D02*
D01*
X02294Y03901*
X02294Y039*
X02294Y039*
X02294Y03899*
X02294Y03899*
X02294Y03898*
X02295Y03898*
X02295Y03897*
X02295Y03897*
X02296Y03896*
X02296Y03896*
X02296Y03896*
X02579Y03609D02*
D01*
X02579Y0361*
X02579Y0361*
X02579Y03611*
X02579Y03612*
X02579Y03612*
X02579Y03613*
X02578Y03613*
X02578Y03614*
X02578Y03614*
X02577Y03614*
X02577Y03615*
X02577Y03615*
X02625Y02278D02*
X02638Y0229D01*
X02651Y02384D02*
X02665Y02398D01*
X02651Y02285D02*
Y02384D01*
X02624Y02459D02*
Y02461D01*
X02604Y02364D02*
Y02431D01*
X02598Y0229D02*
X02604Y02284D01*
X02666Y02284D02*
X02671Y02288D01*
X02604Y01734D02*
Y02284D01*
X02598Y0229D02*
Y02357D01*
X02645Y0227D02*
X02647Y02271D01*
X02671Y02288D02*
Y02291D01*
X02625Y01771D02*
X02626Y0177D01*
X02647Y02271D02*
Y02281D01*
X02625Y01771D02*
Y02278D01*
X02647Y02281D02*
X02651Y02285D01*
X02624Y02459D02*
X02638Y02446D01*
X02598Y02357D02*
X02604Y02364D01*
X02638Y0229D02*
Y02446D01*
X02666Y0164D02*
Y02284D01*
X02389Y01948D02*
Y02398D01*
X02384Y01941D02*
Y01943D01*
X02341Y02447D02*
X02389Y02398D01*
X02384Y01943D02*
X02389Y01948D01*
X02505Y02442D02*
Y02531D01*
X02508Y02533D02*
Y02622D01*
X02505Y02531D02*
X02508Y02533D01*
X02505Y02442D02*
X02519Y02428D01*
X02508Y02622D02*
X02653Y02767D01*
X02259Y02621D02*
Y03261D01*
X02252Y02613D02*
X02259Y02621D01*
X03394Y02011D02*
Y03447D01*
X03336Y01952D02*
X03394Y02011D01*
X04318Y03681D02*
X04393Y03755D01*
X04318Y03507D02*
Y03681D01*
X04393Y03755D02*
Y03976D01*
X03695Y01707D02*
Y03258D01*
X03657Y03296D02*
X03695Y03258D01*
X03732Y01693D02*
X03745Y01679D01*
X03747*
X0371Y01693D02*
X03732D01*
X03695Y01707D02*
X0371Y01693D01*
X03072Y02242D02*
Y03386D01*
X03072Y03386D02*
Y03392D01*
X0307Y03393D02*
X03072Y03392D01*
Y03386D02*
X03072Y03386D01*
X03056Y02226D02*
X03072Y02242D01*
X04437Y03378D02*
Y03661D01*
Y03378D02*
X04438Y03376D01*
Y03354D02*
Y03376D01*
X03492Y02357D02*
Y03296D01*
X03542Y02415D02*
Y03318D01*
X03436Y01996D02*
Y03476D01*
X03437Y03476*
X03622Y02588D02*
X03623Y02587D01*
X03622Y02588D02*
Y03486D01*
X03342Y02263D02*
X03344Y02265D01*
X03302Y01977D02*
Y03344D01*
X03298Y01973D02*
X03302Y01977D01*
X03344Y02265D02*
Y02996D01*
Y03286D02*
X03358Y033D01*
X03344Y02996D02*
Y03286D01*
X03368Y0305D02*
Y03264D01*
X03358Y033D02*
Y03448D01*
X03298Y01971D02*
Y01973D01*
X03799Y02356D02*
Y03201D01*
X02966Y02447D02*
X02979Y0246D01*
X02964Y02298D02*
Y02441D01*
X02955Y02286D02*
X02962Y02292D01*
X03334Y01946D02*
X03334Y01942D01*
X03334Y01834D02*
Y01941D01*
X03329Y01826D02*
X03332Y01829D01*
X03395Y01951D02*
X03434Y0199D01*
X03392Y01871D02*
Y01945D01*
X02208Y02401D02*
X02224Y02417D01*
X02208Y02466D02*
X02222Y02451D01*
X02205Y02472D02*
Y032D01*
X02226Y02423D02*
Y02444D01*
X02222Y02451D02*
X02224Y0245D01*
X02205Y01299D02*
Y02395D01*
X02653Y02767D02*
Y02981D01*
X02462Y03172D02*
X02653Y02981D01*
X02525Y02463D02*
Y02613D01*
X02528Y02618D02*
X02664Y02755D01*
X02667Y02761D02*
Y03155D01*
X02525Y02613D02*
D01*
X02386Y02769D02*
X02494Y02661D01*
X02386Y02769D02*
Y03019D01*
X02687Y02753D02*
Y03353D01*
X02549Y01755D02*
Y02609D01*
D01*
X02552Y02615D02*
X02684Y02747D01*
X02638Y02667D02*
X02692Y02721D01*
X02579Y03486D02*
Y03609D01*
X02294Y03901D02*
Y04126D01*
X02296Y03896D02*
X02577Y03615D01*
X02579Y03609D02*
Y03609D01*
X05577Y02214D02*
X0558D01*
X05584Y02218*
X05586*
X03497Y02344D02*
X03499Y02342D01*
X01363Y01786D02*
X01393Y01816D01*
X01363Y00832D02*
Y01786D01*
X0099Y00687D02*
X01217D01*
X01363Y00832*
X03542Y02415D02*
X03604Y02353D01*
X03509Y03323D02*
X03523Y0331D01*
Y01467D02*
Y0331D01*
Y01467D02*
X03549Y01441D01*
X03604Y0209D02*
Y02353D01*
X01574Y0242D02*
X01619Y02375D01*
Y02121D02*
Y02375D01*
X01574Y0242D02*
Y03596D01*
X01568Y02067D02*
Y02389D01*
X01549Y02465D02*
D01*
Y02407D02*
Y02465D01*
Y02407D02*
X01568Y02389D01*
X01549Y02465D02*
Y03621D01*
X03197Y01714D02*
Y02969D01*
X03197Y0297*
X03491Y03297D02*
X03492Y03296D01*
X03224Y03229D02*
X0323Y03235D01*
X03224Y01661D02*
Y03229D01*
X02998Y02618D02*
Y02972D01*
X03021Y02995D02*
Y03821D01*
X02998Y02972D02*
X03021Y02995D01*
X02993Y02985D02*
Y03751D01*
X02998Y02618D02*
X03013Y02603D01*
X03014Y03828D02*
X03021Y03821D01*
X02979Y02971D02*
X02993Y02985D01*
X03013Y02314D02*
Y02603D01*
X03014Y03828D02*
Y03831D01*
X03056Y01811D02*
Y02226D01*
X03252Y01661D02*
Y03293D01*
X03263Y03303*
X02527Y03294D02*
X02667Y03155D01*
X02634Y03406D02*
X02687Y03353D01*
X02527Y03294D02*
Y03434D01*
X02385Y03019D02*
X02386Y03019D01*
X02385Y03019D02*
Y03298D01*
X02362Y02688D02*
X02429Y02621D01*
X02527Y03434D02*
X02579Y03486D01*
X02519Y02227D02*
Y02428D01*
X02638Y0253D02*
Y02667D01*
X02665Y02398D02*
Y02503D01*
X02638Y0253D02*
X02665Y02503D01*
X02004Y01336D02*
Y03816D01*
X02028Y01361D02*
X02029Y01362D01*
X02579Y0179D02*
Y02281D01*
X02475Y02291D02*
X02478Y02288D01*
X02446Y02275D02*
X0245Y02279D01*
Y02282*
X02446Y01437D02*
Y02275D01*
X02409Y01967D02*
Y02283D01*
X02362Y03298D02*
X02459Y03396D01*
X02434Y03546D02*
X02459Y03521D01*
Y03396D02*
Y03521D01*
X02253Y03847D02*
X02479Y03622D01*
X02385Y03298D02*
X02479Y03391D01*
Y03622*
X02341Y0343D02*
X02389Y03478D01*
X02341Y02447D02*
Y0343D01*
X02389Y03478D02*
Y03481D01*
X02362Y02688D02*
Y03298D01*
X02253Y03847D02*
Y04086D01*
X02299Y01916D02*
Y03491D01*
X02254Y03536D02*
X02299Y03491D01*
X02143Y04106D02*
X02146Y04103D01*
X01979Y04106D02*
X02143D01*
X01925Y0416D02*
X01979Y04106D01*
X01925Y0416D02*
D01*
X01836Y04249D02*
X01925Y0416D01*
X01586Y04314D02*
X01625Y04276D01*
X01393Y04314D02*
X01586D01*
X01625Y04276D02*
X01881D01*
X01345Y04175D02*
Y04266D01*
X01393Y04314*
X02205Y032D02*
Y04144D01*
X02143Y04206D02*
X02205Y04144D01*
X01951Y04206D02*
X02143D01*
X01881Y04276D02*
X01951Y04206D01*
X02043Y04257D02*
X02163D01*
X02294Y04126*
X01681Y04249D02*
X01836D01*
X01631Y04046D02*
Y04199D01*
X01681Y04249*
X01478Y03892D02*
X01631Y04046D01*
X05634Y021D02*
Y02236D01*
Y00947D02*
Y021D01*
X04327Y02307D02*
X04534Y021D01*
X05634*
X04039Y02406D02*
X04062Y02428D01*
X01459Y03147D02*
Y03463D01*
X01478Y03482D02*
Y03892D01*
X01459Y03463D02*
X01478Y03482D01*
X02979Y0246D02*
Y02971D01*
X02274Y01506D02*
Y02286D01*
X02272Y02289D02*
X02274Y02286D01*
X02272Y02289D02*
Y02463D01*
X03439Y0187D02*
Y01874D01*
X03438Y01875D02*
X03439Y01874D01*
X05577Y02214D02*
X05578Y02214D01*
Y02489*
X02694Y02284D02*
X02702Y02292D01*
Y02293*
X02694Y01481D02*
Y02284D01*
X03744Y01711D02*
Y03261D01*
Y01711D02*
X03774Y01681D01*
Y01667D02*
Y01681D01*
X03773Y01666D02*
X03774Y01667D01*
X05578Y0089D02*
X05634Y00947D01*
X0392Y03102D02*
X03939Y03121D01*
X0392Y01685D02*
Y03102D01*
Y01685D02*
X03924Y01681D01*
Y01536D02*
Y01681D01*
X03374Y0327D02*
Y03273D01*
X03368Y03264D02*
X03374Y0327D01*
X04062Y02428D02*
Y02595D01*
X03789Y03235D02*
X03806D01*
X03769Y03215D02*
X03789Y03235D01*
X03769Y01726D02*
Y03215D01*
Y01726D02*
X03803Y01692D01*
Y01691D02*
Y01692D01*
X0138Y04202D02*
X01438Y0426D01*
X0138Y03617D02*
Y04202D01*
Y03617D02*
X0144Y03557D01*
X03509Y03323D02*
Y03766D01*
X03519Y03776*
Y04071*
X03504Y04086D02*
X03519Y04071D01*
X03492Y02357D02*
X03501Y02348D01*
X03497Y02344D02*
X03501Y02348D01*
X03834Y01481D02*
Y02321D01*
X03799Y02356D02*
X03834Y02321D01*
X0384Y02861D02*
X03854Y02875D01*
X0384Y02368D02*
Y02861D01*
Y02368D02*
X03894Y02314D01*
X03824Y02361D02*
X03864Y02321D01*
Y01511D02*
Y02321D01*
X03604Y0209D02*
X03613Y02081D01*
Y01735D02*
Y02081D01*
X03589Y01711D02*
X03613Y01735D01*
X03498Y02341D02*
X03499Y02342D01*
X02478Y00937D02*
Y02288D01*
X02985Y02287D02*
X03013Y02314D01*
X02205Y01299D02*
X02206Y01298D01*
X02502Y01316D02*
Y0221D01*
X02519Y02227*
X0292Y01537D02*
Y02428D01*
X02919Y01536D02*
X0292Y01537D01*
X02942Y02286D02*
X02955D01*
X02643Y01711D02*
X02648Y01716D01*
X02643Y01616D02*
Y01711D01*
X02648Y01716D02*
Y02265D01*
X02647Y02266D02*
Y02272D01*
Y02266D02*
X02648Y02265D01*
X02726Y01599D02*
Y02293D01*
X02719Y01592D02*
X02726Y01599D01*
X02719Y01591D02*
Y01592D01*
X01884Y02071D02*
Y03601D01*
X02029Y01362D02*
Y03836D01*
X02059Y01386D02*
Y03871D01*
X01754Y02126D02*
Y03661D01*
X01549Y03621D02*
D01*
X01719Y01536D02*
X01779Y01596D01*
Y04156*
X02894Y01561D02*
Y02431D01*
X03894Y01566D02*
Y02314D01*
X03438Y01875D02*
X03469Y01906D01*
X03854Y02875D02*
Y03151D01*
X03829Y02873D02*
Y03176D01*
X03824Y02361D02*
Y02868D01*
X03829Y02873*
X03469Y01906D02*
Y03456D01*
G54D162*
X01849Y00271D02*
Y03701D01*
G54D170*
X04327Y02307D03*
G54D172*
X04062Y02595D03*
X05578Y02489D03*
Y0089D03*
G54D178*
X02043Y04257D03*
X01457Y04253D03*
G54D181*
X02645Y0227D03*
X02671Y02291D03*
X04393Y03976D03*
X04318Y03507D03*
X03657Y03296D03*
X03747Y01679D03*
X0307Y03393D03*
X04438Y03354D03*
X03542Y03318D03*
X03437Y03476D03*
X03622Y03486D03*
X04437Y03661D03*
X03344Y02996D03*
X03342Y02263D03*
X03368Y0305D03*
X03799Y03201D03*
X02462Y03172D03*
X02252Y02613D03*
X02579Y02281D03*
X02708Y00976D03*
X03803Y01691D03*
X0245Y02282D03*
X03773Y01666D03*
X0292Y02428D03*
X03864Y01511D03*
X02799Y00976D03*
X03298Y01971D03*
X02894Y02431D03*
X02759Y00795D03*
X02726Y02293D03*
X02985Y02287D03*
X02625Y00795D03*
X02702Y02289D03*
X02893Y00795D03*
X02732D03*
X02599Y02436D03*
X02475Y02291D03*
X01568Y02067D03*
X02826Y00976D03*
X02942Y02286D03*
X02598Y00795D03*
X01719Y01536D03*
X02272Y02463D03*
X02681Y00976D03*
X03392Y01871D03*
X02494Y02661D03*
X02409Y02283D03*
X01619Y02121D03*
X01754Y02126D03*
X03924Y01536D03*
X03549Y01441D03*
X02624Y02461D03*
X03329Y01826D03*
X01884Y02071D03*
X03834Y01481D03*
X02862Y00795D03*
X03894Y01566D03*
X03224Y01661D03*
X03197Y01714D03*
X03439Y0187D03*
X03252Y01661D03*
X02692Y02721D03*
X02511Y00405D03*
X0298Y00409D03*
X02821Y00407D03*
X02469Y0041D03*
X02854Y00405D03*
X02665D03*
X02704D03*
X0235D03*
X02389D03*
X03019D03*
X01393Y01816D03*
X0099Y00687D03*
X03197Y0297D03*
X03491Y03103D03*
X0323Y03235D03*
X03358Y03448D03*
X03056Y01811D03*
X02254Y03536D03*
X02579Y03486D03*
X02389Y03481D03*
X02434Y03546D03*
X02634Y03406D03*
X02004Y01336D03*
X02028Y01361D03*
X02549Y01755D03*
X02146Y04103D03*
X02253Y04086D03*
X01345Y04175D03*
X04039Y02406D03*
X03263Y03303D03*
X01852Y00255D03*
X01832Y00287D03*
X01852D03*
X05577Y02214D03*
X02694Y01481D03*
X02384Y01941D03*
X03744Y03261D03*
X05634Y02236D03*
X02626Y0177D03*
X03939Y03121D03*
X02604Y01734D03*
X02299Y01916D03*
X02579Y0179D03*
X02259Y03261D03*
X03374Y03273D03*
X03806Y03235D03*
X01459Y03147D03*
X0144Y03557D03*
X03623Y02587D03*
X03491Y03297D03*
X03394Y03447D03*
X03589Y01711D03*
X02478Y00937D03*
X02206Y01298D03*
X02205Y032D03*
X02502Y01316D03*
X02525Y02463D03*
X03498Y02341D03*
X02429Y02621D03*
X02446Y01437D03*
X02409Y01967D03*
X02643Y01616D03*
X02666Y0164D03*
X01884Y03601D03*
X01754Y03661D03*
X01549Y03621D03*
X01574Y03596D03*
X02084Y03896D03*
X02083Y01411D03*
X02059Y01386D03*
Y03871D03*
X02029Y03836D03*
X02004Y03816D03*
X02993Y03751D03*
X03014Y03831D03*
X02894Y01561D03*
X02919Y01536D03*
X02274Y01506D03*
X02719Y01591D03*
X01779Y04156D03*
X03504Y04086D03*
X03854Y03151D03*
X03829Y03176D03*
X03302Y03344D03*
X03469Y03456D03*
X01849Y03701D03*
M02*